(kicad_pcb
	(version 20260206)
	(generator "pcbnew")
	(generator_version "10.0")
	(general
		(thickness 1.6)
		(legacy_teardrops no)
	)
	(paper "A4")
	(title_block
		(title "01162023_DA0F0TEBIF0_F0T_Expander_BD_F_brd_V02_OCP.brd")
		(comment 1 "Grand Teton / footprints 7157-7163 of 9728")
	)
	(layers
		(0 "F.Cu" signal "TOP")
		(4 "In1.Cu" signal "GND")
		(6 "In2.Cu" signal "VCC")
		(8 "In3.Cu" signal "VCC1")
		(10 "In4.Cu" signal "GND1")
		(12 "In5.Cu" signal "IN1")
		(14 "In6.Cu" signal "GND2")
		(16 "In7.Cu" signal "IN2")
		(18 "In8.Cu" signal "GND3")
		(20 "In9.Cu" signal "IN3")
		(22 "In10.Cu" signal "GND4")
		(24 "In11.Cu" signal "IN4")
		(26 "In12.Cu" signal "GND5")
		(28 "In13.Cu" signal "IN5")
		(30 "In14.Cu" signal "GND6")
		(32 "In15.Cu" signal "IN6")
		(34 "In16.Cu" signal "GND7")
		(2 "B.Cu" signal "BOTTOM")
		(9 "F.Adhes" user "F.Adhesive")
		(11 "B.Adhes" user "B.Adhesive")
		(13 "F.Paste" user "Package Geometry/Pastemask Top")
		(15 "B.Paste" user "Package Geometry/Pastemask Bottom")
		(5 "F.SilkS" user "Ref Des/Silkscreen Top")
		(7 "B.SilkS" user "Ref Des/Silkscreen Bottom")
		(1 "F.Mask" user "Board Geometry/Soldermask Top")
		(3 "B.Mask" user "Board Geometry/Soldermask Bottom")
		(17 "Dwgs.User" user "User.Drawings")
		(19 "Cmts.User" user "User.Comments")
		(21 "Eco1.User" user "User.Eco1")
		(23 "Eco2.User" user "User.Eco2")
		(25 "Edge.Cuts" user "Board Geometry/Outline")
		(27 "Margin" user)
		(31 "F.CrtYd" user "Package Geometry/Place Bound Top")
		(29 "B.CrtYd" user "Package Geometry/Place Bound Bottom")
		(35 "F.Fab" user "Ref Des/Assembly Top")
		(33 "B.Fab" user "Ref Des/Assembly Bottom")
	)
	(footprint ""
		(layer "B.Cu")
		(at 414.151318 -305.399948 -90)
		(property "Reference" "C3483"
			(at 0 0 90)
			(layer "B.SilkS")
			(hide yes)
			(effects
				(font
					(size 1.27 1.27)
				)
				(justify mirror)
			)
		)
		(property "Value" ""
			(at 0 0 90)
			(layer "B.Fab")
			(effects
				(font
					(size 1.27 1.27)
				)
				(justify mirror)
			)
		)
		(duplicate_pad_numbers_are_jumpers no)
		(fp_line
			(start -0.299974 0.150114)
			(end 0.299974 0.150114)
			(stroke
				(width 0.1)
				(type default)
			)
			(layer "B.Fab")
		)
		(fp_line
			(start 0.299974 0.150114)
			(end 0.299974 -0.150114)
			(stroke
				(width 0.1)
				(type default)
			)
			(layer "B.Fab")
		)
		(fp_line
			(start -0.299974 -0.150114)
			(end -0.299974 0.150114)
			(stroke
				(width 0.1)
				(type default)
			)
			(layer "B.Fab")
		)
		(fp_line
			(start 0.299974 -0.150114)
			(end -0.299974 -0.150114)
			(stroke
				(width 0.1)
				(type default)
			)
			(layer "B.Fab")
		)
		(pad "1" smd rect
			(at 0.2667 0 90)
			(size 0.3048 0.381)
			(layers "B.Cu" "B.Mask" "B.Paste")
			(net "P1V25_SERDES_VDDPLL_PEX3")
		)
		(pad "2" smd rect
			(at -0.2667 0 90)
			(size 0.3048 0.381)
			(layers "B.Cu" "B.Mask" "B.Paste")
			(net "GND")
		)
	)
	(footprint ""
		(layer "B.Cu")
		(at 389.899906 -288.774886 90)
		(property "Reference" "R6160"
			(at 0 0 90)
			(layer "B.SilkS")
			(hide yes)
			(effects
				(font
					(size 1.27 1.27)
				)
				(justify mirror)
			)
		)
		(property "Value" ""
			(at 0 0 90)
			(layer "B.Fab")
			(effects
				(font
					(size 1.27 1.27)
				)
				(justify mirror)
			)
		)
		(duplicate_pad_numbers_are_jumpers no)
		(fp_line
			(start 0.7874 -0.4064)
			(end -0.7874 -0.4064)
			(stroke
				(width 0.1524)
				(type default)
			)
			(layer "B.SilkS")
		)
		(fp_line
			(start -0.7874 -0.4064)
			(end -0.7874 0.4064)
			(stroke
				(width 0.1524)
				(type default)
			)
			(layer "B.SilkS")
		)
		(fp_line
			(start 0.7874 0.4064)
			(end 0.7874 -0.4064)
			(stroke
				(width 0.1524)
				(type default)
			)
			(layer "B.SilkS")
		)
		(fp_line
			(start -0.7874 0.4064)
			(end 0.7874 0.4064)
			(stroke
				(width 0.1524)
				(type default)
			)
			(layer "B.SilkS")
		)
		(fp_line
			(start 0.67945 -0.305054)
			(end 0.12065 -0.305054)
			(stroke
				(width 0.1)
				(type default)
			)
			(layer "B.Fab")
		)
		(fp_line
			(start 0.12065 -0.305054)
			(end 0.12065 -0.2794)
			(stroke
				(width 0.1)
				(type default)
			)
			(layer "B.Fab")
		)
		(fp_line
			(start -0.12065 -0.3048)
			(end -0.67945 -0.3048)
			(stroke
				(width 0.1)
				(type default)
			)
			(layer "B.Fab")
		)
		(fp_line
			(start -0.67945 -0.3048)
			(end -0.67945 0.3048)
			(stroke
				(width 0.1)
				(type default)
			)
			(layer "B.Fab")
		)
		(fp_line
			(start 0.12065 -0.2794)
			(end -0.12065 -0.2794)
			(stroke
				(width 0.1)
				(type default)
			)
			(layer "B.Fab")
		)
		(fp_line
			(start -0.12065 -0.2794)
			(end -0.12065 -0.3048)
			(stroke
				(width 0.1)
				(type default)
			)
			(layer "B.Fab")
		)
		(fp_line
			(start 0.12065 0.2794)
			(end 0.12065 0.3048)
			(stroke
				(width 0.1)
				(type default)
			)
			(layer "B.Fab")
		)
		(fp_line
			(start -0.120396 0.2794)
			(end 0.12065 0.2794)
			(stroke
				(width 0.1)
				(type default)
			)
			(layer "B.Fab")
		)
		(fp_line
			(start 0.67945 0.3048)
			(end 0.67945 -0.305054)
			(stroke
				(width 0.1)
				(type default)
			)
			(layer "B.Fab")
		)
		(fp_line
			(start 0.12065 0.3048)
			(end 0.67945 0.3048)
			(stroke
				(width 0.1)
				(type default)
			)
			(layer "B.Fab")
		)
		(fp_line
			(start -0.120396 0.3048)
			(end -0.120396 0.2794)
			(stroke
				(width 0.1)
				(type default)
			)
			(layer "B.Fab")
		)
		(fp_line
			(start -0.67945 0.3048)
			(end -0.120396 0.3048)
			(stroke
				(width 0.1)
				(type default)
			)
			(layer "B.Fab")
		)
		(pad "1" smd circle
			(at 0.40005 0 270)
			(size 0 0)
			(layers "B.Cu" "B.Mask" "B.Paste")
			(net "SPI_PEX3_CS_N")
		)
		(pad "2" smd circle
			(at -0.40005 0 270)
			(size 0 0)
			(layers "B.Cu" "B.Mask" "B.Paste")
			(net "P1V8_PEX")
		)
	)
	(footprint ""
		(layer "B.Cu")
		(at 5.617718 -264.586466)
		(property "Reference" "L83"
			(at 0 0 0)
			(layer "B.SilkS")
			(hide yes)
			(effects
				(font
					(size 1.27 1.27)
				)
				(justify mirror)
			)
		)
		(property "Value" ""
			(at 0 0 0)
			(layer "B.Fab")
			(effects
				(font
					(size 1.27 1.27)
				)
				(justify mirror)
			)
		)
		(duplicate_pad_numbers_are_jumpers no)
		(fp_line
			(start -2.248154 -4.9911)
			(end 2.248154 -4.9911)
			(stroke
				(width 0.1524)
				(type default)
			)
			(layer "B.SilkS")
		)
		(fp_line
			(start -2.248154 -2.077974)
			(end -2.248154 -4.9911)
			(stroke
				(width 0.1524)
				(type default)
			)
			(layer "B.SilkS")
		)
		(fp_line
			(start -2.248154 4.9911)
			(end -2.248154 2.20472)
			(stroke
				(width 0.1524)
				(type default)
			)
			(layer "B.SilkS")
		)
		(fp_line
			(start 2.248154 -4.9911)
			(end 2.248154 -2.077974)
			(stroke
				(width 0.1524)
				(type default)
			)
			(layer "B.SilkS")
		)
		(fp_line
			(start 2.248154 2.20472)
			(end 2.248154 4.9911)
			(stroke
				(width 0.1524)
				(type default)
			)
			(layer "B.SilkS")
		)
		(fp_line
			(start 2.248154 4.9911)
			(end -2.248154 4.9911)
			(stroke
				(width 0.1524)
				(type default)
			)
			(layer "B.SilkS")
		)
		(fp_line
			(start -1.700022 -0.899922)
			(end 1.700022 -0.899922)
			(stroke
				(width 0.1)
				(type default)
			)
			(layer "B.Fab")
		)
		(fp_line
			(start -1.700022 0.899922)
			(end -1.700022 -0.899922)
			(stroke
				(width 0.1)
				(type default)
			)
			(layer "B.Fab")
		)
		(fp_line
			(start 1.700022 -0.899922)
			(end 1.700022 0.899922)
			(stroke
				(width 0.1)
				(type default)
			)
			(layer "B.Fab")
		)
		(fp_line
			(start 1.700022 0.899922)
			(end -1.700022 0.899922)
			(stroke
				(width 0.1)
				(type default)
			)
			(layer "B.Fab")
		)
		(pad "1" smd rect
			(at 1.575054 0 180)
			(size 1.1684 9.8044)
			(layers "B.Cu" "B.Mask" "B.Paste")
			(net "P1V25_PEX0")
		)
		(pad "2" smd rect
			(at -1.575054 0 180)
			(size 1.1684 9.8044)
			(layers "B.Cu" "B.Mask" "B.Paste")
			(net "P1V25_SERDES_VDDPLL_PEX0")
		)
	)
	(footprint ""
		(layer "B.Cu")
		(at 110.884208 -88.81745)
		(property "Reference" "C2668"
			(at 0 0 0)
			(layer "B.SilkS")
			(hide yes)
			(effects
				(font
					(size 1.27 1.27)
				)
				(justify mirror)
			)
		)
		(property "Value" ""
			(at 0 0 0)
			(layer "B.Fab")
			(effects
				(font
					(size 1.27 1.27)
				)
				(justify mirror)
			)
		)
		(duplicate_pad_numbers_are_jumpers no)
		(fp_line
			(start -0.7874 -0.4064)
			(end -0.7874 0.4064)
			(stroke
				(width 0.1524)
				(type default)
			)
			(layer "B.SilkS")
		)
		(fp_line
			(start -0.7874 0.4064)
			(end 0.7874 0.4064)
			(stroke
				(width 0.1524)
				(type default)
			)
			(layer "B.SilkS")
		)
		(fp_line
			(start 0.7874 -0.4064)
			(end -0.7874 -0.4064)
			(stroke
				(width 0.1524)
				(type default)
			)
			(layer "B.SilkS")
		)
		(fp_line
			(start 0.7874 0.4064)
			(end 0.7874 -0.4064)
			(stroke
				(width 0.1524)
				(type default)
			)
			(layer "B.SilkS")
		)
		(fp_line
			(start -0.67945 -0.3048)
			(end -0.67945 0.3048)
			(stroke
				(width 0.1)
				(type default)
			)
			(layer "B.Fab")
		)
		(fp_line
			(start -0.67945 0.3048)
			(end -0.120396 0.3048)
			(stroke
				(width 0.1)
				(type default)
			)
			(layer "B.Fab")
		)
		(fp_line
			(start -0.12065 -0.3048)
			(end -0.67945 -0.3048)
			(stroke
				(width 0.1)
				(type default)
			)
			(layer "B.Fab")
		)
		(fp_line
			(start -0.12065 -0.2794)
			(end -0.12065 -0.3048)
			(stroke
				(width 0.1)
				(type default)
			)
			(layer "B.Fab")
		)
		(fp_line
			(start -0.120396 0.2794)
			(end 0.12065 0.2794)
			(stroke
				(width 0.1)
				(type default)
			)
			(layer "B.Fab")
		)
		(fp_line
			(start -0.120396 0.3048)
			(end -0.120396 0.2794)
			(stroke
				(width 0.1)
				(type default)
			)
			(layer "B.Fab")
		)
		(fp_line
			(start 0.12065 -0.305054)
			(end 0.12065 -0.2794)
			(stroke
				(width 0.1)
				(type default)
			)
			(layer "B.Fab")
		)
		(fp_line
			(start 0.12065 -0.2794)
			(end -0.12065 -0.2794)
			(stroke
				(width 0.1)
				(type default)
			)
			(layer "B.Fab")
		)
		(fp_line
			(start 0.12065 0.2794)
			(end 0.12065 0.3048)
			(stroke
				(width 0.1)
				(type default)
			)
			(layer "B.Fab")
		)
		(fp_line
			(start 0.12065 0.3048)
			(end 0.67945 0.3048)
			(stroke
				(width 0.1)
				(type default)
			)
			(layer "B.Fab")
		)
		(fp_line
			(start 0.67945 -0.305054)
			(end 0.12065 -0.305054)
			(stroke
				(width 0.1)
				(type default)
			)
			(layer "B.Fab")
		)
		(fp_line
			(start 0.67945 0.3048)
			(end 0.67945 -0.305054)
			(stroke
				(width 0.1)
				(type default)
			)
			(layer "B.Fab")
		)
		(pad "1" smd circle
			(at 0.40005 0 180)
			(size 0 0)
			(layers "B.Cu" "B.Mask" "B.Paste")
			(net "P3V3_VDD_9ZXL0851_0_7")
		)
		(pad "2" smd circle
			(at -0.40005 0 180)
			(size 0 0)
			(layers "B.Cu" "B.Mask" "B.Paste")
			(net "GND")
		)
	)
	(footprint ""
		(layer "B.Cu")
		(at 137.689336 -173.827186 90)
		(property "Reference" "C2657"
			(at 0 0 90)
			(layer "B.SilkS")
			(hide yes)
			(effects
				(font
					(size 1.27 1.27)
				)
				(justify mirror)
			)
		)
		(property "Value" ""
			(at 0 0 90)
			(layer "B.Fab")
			(effects
				(font
					(size 1.27 1.27)
				)
				(justify mirror)
			)
		)
		(duplicate_pad_numbers_are_jumpers no)
		(fp_line
			(start 1.2954 -0.5842)
			(end -1.2954 -0.5842)
			(stroke
				(width 0.1524)
				(type default)
			)
			(layer "B.SilkS")
		)
		(fp_line
			(start -1.2954 -0.5842)
			(end -1.2954 0.5842)
			(stroke
				(width 0.1524)
				(type default)
			)
			(layer "B.SilkS")
		)
		(fp_line
			(start 1.2954 0.5842)
			(end 1.2954 -0.5842)
			(stroke
				(width 0.1524)
				(type default)
			)
			(layer "B.SilkS")
		)
		(fp_line
			(start -1.2954 0.5842)
			(end 1.2954 0.5842)
			(stroke
				(width 0.1524)
				(type default)
			)
			(layer "B.SilkS")
		)
		(fp_line
			(start 0.8636 -0.4572)
			(end -0.8636 -0.4572)
			(stroke
				(width 0.1)
				(type default)
			)
			(layer "B.Fab")
		)
		(fp_line
			(start -0.8636 -0.4572)
			(end -0.8636 -0.4064)
			(stroke
				(width 0.1)
				(type default)
			)
			(layer "B.Fab")
		)
		(fp_line
			(start 1.1938 -0.4064)
			(end 0.8636 -0.4064)
			(stroke
				(width 0.1)
				(type default)
			)
			(layer "B.Fab")
		)
		(fp_line
			(start 0.8636 -0.4064)
			(end 0.8636 -0.4572)
			(stroke
				(width 0.1)
				(type default)
			)
			(layer "B.Fab")
		)
		(fp_line
			(start -0.8636 -0.4064)
			(end -1.1938 -0.4064)
			(stroke
				(width 0.1)
				(type default)
			)
			(layer "B.Fab")
		)
		(fp_line
			(start -1.1938 -0.4064)
			(end -1.1938 0.4064)
			(stroke
				(width 0.1)
				(type default)
			)
			(layer "B.Fab")
		)
		(fp_line
			(start 1.1938 0.4064)
			(end 1.1938 -0.4064)
			(stroke
				(width 0.1)
				(type default)
			)
			(layer "B.Fab")
		)
		(fp_line
			(start 0.8636 0.4064)
			(end 1.1938 0.4064)
			(stroke
				(width 0.1)
				(type default)
			)
			(layer "B.Fab")
		)
		(fp_line
			(start -0.8636 0.4064)
			(end -0.8636 0.4572)
			(stroke
				(width 0.1)
				(type default)
			)
			(layer "B.Fab")
		)
		(fp_line
			(start -1.1938 0.4064)
			(end -0.8636 0.4064)
			(stroke
				(width 0.1)
				(type default)
			)
			(layer "B.Fab")
		)
		(fp_line
			(start 0.8636 0.4572)
			(end 0.8636 0.4064)
			(stroke
				(width 0.1)
				(type default)
			)
			(layer "B.Fab")
		)
		(fp_line
			(start -0.8636 0.4572)
			(end 0.8636 0.4572)
			(stroke
				(width 0.1)
				(type default)
			)
			(layer "B.Fab")
		)
		(pad "1" smd rect
			(at 0.7366 0)
			(size 0.7112 0.8128)
			(layers "B.Cu" "B.Mask" "B.Paste")
			(net "P3V3_DB2000QL_VDD")
		)
		(pad "2" smd rect
			(at -0.7366 0)
			(size 0.7112 0.8128)
			(layers "B.Cu" "B.Mask" "B.Paste")
			(net "GND")
		)
	)
	(footprint ""
		(layer "B.Cu")
		(at 304.093626 -239.976406 90)
		(property "Reference" "R4101"
			(at 0 0 90)
			(layer "B.SilkS")
			(hide yes)
			(effects
				(font
					(size 1.27 1.27)
				)
				(justify mirror)
			)
		)
		(property "Value" ""
			(at 0 0 90)
			(layer "B.Fab")
			(effects
				(font
					(size 1.27 1.27)
				)
				(justify mirror)
			)
		)
		(duplicate_pad_numbers_are_jumpers no)
		(fp_line
			(start 0.7874 -0.4064)
			(end -0.7874 -0.4064)
			(stroke
				(width 0.1524)
				(type default)
			)
			(layer "B.SilkS")
		)
		(fp_line
			(start -0.7874 -0.4064)
			(end -0.7874 0.4064)
			(stroke
				(width 0.1524)
				(type default)
			)
			(layer "B.SilkS")
		)
		(fp_line
			(start 0.7874 0.4064)
			(end 0.7874 -0.4064)
			(stroke
				(width 0.1524)
				(type default)
			)
			(layer "B.SilkS")
		)
		(fp_line
			(start -0.7874 0.4064)
			(end 0.7874 0.4064)
			(stroke
				(width 0.1524)
				(type default)
			)
			(layer "B.SilkS")
		)
		(fp_line
			(start 0.67945 -0.305054)
			(end 0.12065 -0.305054)
			(stroke
				(width 0.1)
				(type default)
			)
			(layer "B.Fab")
		)
		(fp_line
			(start 0.12065 -0.305054)
			(end 0.12065 -0.2794)
			(stroke
				(width 0.1)
				(type default)
			)
			(layer "B.Fab")
		)
		(fp_line
			(start -0.12065 -0.3048)
			(end -0.67945 -0.3048)
			(stroke
				(width 0.1)
				(type default)
			)
			(layer "B.Fab")
		)
		(fp_line
			(start -0.67945 -0.3048)
			(end -0.67945 0.3048)
			(stroke
				(width 0.1)
				(type default)
			)
			(layer "B.Fab")
		)
		(fp_line
			(start 0.12065 -0.2794)
			(end -0.12065 -0.2794)
			(stroke
				(width 0.1)
				(type default)
			)
			(layer "B.Fab")
		)
		(fp_line
			(start -0.12065 -0.2794)
			(end -0.12065 -0.3048)
			(stroke
				(width 0.1)
				(type default)
			)
			(layer "B.Fab")
		)
		(fp_line
			(start 0.12065 0.2794)
			(end 0.12065 0.3048)
			(stroke
				(width 0.1)
				(type default)
			)
			(layer "B.Fab")
		)
		(fp_line
			(start -0.120396 0.2794)
			(end 0.12065 0.2794)
			(stroke
				(width 0.1)
				(type default)
			)
			(layer "B.Fab")
		)
		(fp_line
			(start 0.67945 0.3048)
			(end 0.67945 -0.305054)
			(stroke
				(width 0.1)
				(type default)
			)
			(layer "B.Fab")
		)
		(fp_line
			(start 0.12065 0.3048)
			(end 0.67945 0.3048)
			(stroke
				(width 0.1)
				(type default)
			)
			(layer "B.Fab")
		)
		(fp_line
			(start -0.120396 0.3048)
			(end -0.120396 0.2794)
			(stroke
				(width 0.1)
				(type default)
			)
			(layer "B.Fab")
		)
		(fp_line
			(start -0.67945 0.3048)
			(end -0.120396 0.3048)
			(stroke
				(width 0.1)
				(type default)
			)
			(layer "B.Fab")
		)
		(pad "1" smd circle
			(at 0.40005 0 270)
			(size 0 0)
			(layers "B.Cu" "B.Mask" "B.Paste")
			(net "SMB_MB_BMC_ISO_SCL")
		)
		(pad "2" smd circle
			(at -0.40005 0 270)
			(size 0 0)
			(layers "B.Cu" "B.Mask" "B.Paste")
			(net "P3V3_AUX")
		)
	)
	(footprint ""
		(layer "B.Cu")
		(at 180.02504 -297.79976 90)
		(property "Reference" "C1384"
			(at 0 0 90)
			(layer "B.SilkS")
			(hide yes)
			(effects
				(font
					(size 1.27 1.27)
				)
				(justify mirror)
			)
		)
		(property "Value" ""
			(at 0 0 90)
			(layer "B.Fab")
			(effects
				(font
					(size 1.27 1.27)
				)
				(justify mirror)
			)
		)
		(duplicate_pad_numbers_are_jumpers no)
		(fp_line
			(start 0.299974 -0.150114)
			(end -0.299974 -0.150114)
			(stroke
				(width 0.1)
				(type default)
			)
			(layer "B.Fab")
		)
		(fp_line
			(start -0.299974 -0.150114)
			(end -0.299974 0.150114)
			(stroke
				(width 0.1)
				(type default)
			)
			(layer "B.Fab")
		)
		(fp_line
			(start 0.299974 0.150114)
			(end 0.299974 -0.150114)
			(stroke
				(width 0.1)
				(type default)
			)
			(layer "B.Fab")
		)
		(fp_line
			(start -0.299974 0.150114)
			(end 0.299974 0.150114)
			(stroke
				(width 0.1)
				(type default)
			)
			(layer "B.Fab")
		)
		(pad "1" smd rect
			(at 0.2667 0 270)
			(size 0.3048 0.381)
			(layers "B.Cu" "B.Mask" "B.Paste")
			(net "P0V8_PEX1")
		)
		(pad "2" smd rect
			(at -0.2667 0 270)
			(size 0.3048 0.381)
			(layers "B.Cu" "B.Mask" "B.Paste")
			(net "GND")
		)
	)
)
